(kicad_pcb
	(version 20260206)
	(generator "pcbnew")
	(generator_version "10.0")
	(general
		(thickness 1.6)
		(legacy_teardrops no)
	)
	(paper "A4")
	(title_block
		(title "03242023_DA0F0TMBIJ0_F0T_Motherboard_J_brd_V01_OCP.brd")
		(comment 1 "Grand Teton / footprints 3832-3832 of 6105")
	)
	(layers
		(0 "F.Cu" signal "TOP")
		(4 "In1.Cu" signal "GND")
		(6 "In2.Cu" signal "IN1")
		(8 "In3.Cu" signal "GND1")
		(10 "In4.Cu" signal "IN2")
		(12 "In5.Cu" signal "GND2")
		(14 "In6.Cu" signal "IN3")
		(16 "In7.Cu" signal "GND3")
		(18 "In8.Cu" signal "VCC")
		(20 "In9.Cu" signal "VCC1")
		(22 "In10.Cu" signal "GND4")
		(24 "In11.Cu" signal "IN4")
		(26 "In12.Cu" signal "GND5")
		(28 "In13.Cu" signal "IN5")
		(30 "In14.Cu" signal "GND6")
		(32 "In15.Cu" signal "IN6")
		(34 "In16.Cu" signal "GND7")
		(2 "B.Cu" signal "BOTTOM")
		(9 "F.Adhes" user "F.Adhesive")
		(11 "B.Adhes" user "B.Adhesive")
		(13 "F.Paste" user "Package Geometry/Pastemask Top")
		(15 "B.Paste" user "Package Geometry/Pastemask Bottom")
		(5 "F.SilkS" user "Ref Des/Silkscreen Top")
		(7 "B.SilkS" user "Ref Des/Silkscreen Bottom")
		(1 "F.Mask" user "Board Geometry/Soldermask Top")
		(3 "B.Mask" user "Board Geometry/Soldermask Bottom")
		(17 "Dwgs.User" user "User.Drawings")
		(19 "Cmts.User" user "User.Comments")
		(21 "Eco1.User" user "User.Eco1")
		(23 "Eco2.User" user "User.Eco2")
		(25 "Edge.Cuts" user "Board Geometry/Outline")
		(27 "Margin" user)
		(31 "F.CrtYd" user "Package Geometry/Place Bound Top")
		(29 "B.CrtYd" user "Package Geometry/Place Bound Bottom")
		(35 "F.Fab" user "Ref Des/Assembly Top")
		(33 "B.Fab" user "Ref Des/Assembly Bottom")
	)
	(footprint ""
		(layer "F.Cu")
		(at 120.326658 -15.526766)
		(property "Reference" "R4193"
			(at 0 0 0)
			(layer "F.SilkS")
			(hide yes)
			(effects
				(font
					(size 1.27 1.27)
				)
			)
		)
		(property "Value" ""
			(at 0 0 0)
			(layer "F.Fab")
			(effects
				(font
					(size 1.27 1.27)
				)
			)
		)
		(duplicate_pad_numbers_are_jumpers no)
		(fp_line
			(start -0.7874 -0.4064)
			(end 0.7874 -0.4064)
			(stroke
				(width 0.1524)
				(type default)
			)
			(layer "F.SilkS")
		)
		(fp_line
			(start -0.7874 0.4064)
			(end -0.7874 -0.4064)
			(stroke
				(width 0.1524)
				(type default)
			)
			(layer "F.SilkS")
		)
		(fp_line
			(start 0.7874 -0.4064)
			(end 0.7874 0.4064)
			(stroke
				(width 0.1524)
				(type default)
			)
			(layer "F.SilkS")
		)
		(fp_line
			(start 0.7874 0.4064)
			(end -0.7874 0.4064)
			(stroke
				(width 0.1524)
				(type default)
			)
			(layer "F.SilkS")
		)
		(fp_line
			(start -0.67945 -0.305054)
			(end -0.12065 -0.305054)
			(stroke
				(width 0.1)
				(type default)
			)
			(layer "F.Fab")
		)
		(fp_line
			(start -0.67945 0.3048)
			(end -0.67945 -0.305054)
			(stroke
				(width 0.1)
				(type default)
			)
			(layer "F.Fab")
		)
		(fp_line
			(start -0.12065 -0.305054)
			(end -0.12065 -0.2794)
			(stroke
				(width 0.1)
				(type default)
			)
			(layer "F.Fab")
		)
		(fp_line
			(start -0.12065 -0.2794)
			(end 0.12065 -0.2794)
			(stroke
				(width 0.1)
				(type default)
			)
			(layer "F.Fab")
		)
		(fp_line
			(start -0.12065 0.2794)
			(end -0.12065 0.3048)
			(stroke
				(width 0.1)
				(type default)
			)
			(layer "F.Fab")
		)
		(fp_line
			(start -0.12065 0.3048)
			(end -0.67945 0.3048)
			(stroke
				(width 0.1)
				(type default)
			)
			(layer "F.Fab")
		)
		(fp_line
			(start 0.120396 0.2794)
			(end -0.12065 0.2794)
			(stroke
				(width 0.1)
				(type default)
			)
			(layer "F.Fab")
		)
		(fp_line
			(start 0.120396 0.3048)
			(end 0.120396 0.2794)
			(stroke
				(width 0.1)
				(type default)
			)
			(layer "F.Fab")
		)
		(fp_line
			(start 0.12065 -0.3048)
			(end 0.67945 -0.3048)
			(stroke
				(width 0.1)
				(type default)
			)
			(layer "F.Fab")
		)
		(fp_line
			(start 0.12065 -0.2794)
			(end 0.12065 -0.3048)
			(stroke
				(width 0.1)
				(type default)
			)
			(layer "F.Fab")
		)
		(fp_line
			(start 0.67945 -0.3048)
			(end 0.67945 0.3048)
			(stroke
				(width 0.1)
				(type default)
			)
			(layer "F.Fab")
		)
		(fp_line
			(start 0.67945 0.3048)
			(end 0.120396 0.3048)
			(stroke
				(width 0.1)
				(type default)
			)
			(layer "F.Fab")
		)
		(pad "1" smd circle
			(at -0.40005 0)
			(size 0 0)
			(layers "F.Cu" "F.Mask" "F.Paste")
			(net "U273_3_ADD1")
		)
		(pad "2" smd circle
			(at 0.40005 0)
			(size 0 0)
			(layers "F.Cu" "F.Mask" "F.Paste")
			(net "GND")
		)
	)
)
